# S9S_MB_2U (Grand Teton) — schematic netlist excerpt (pin names and nets, part order shuffled) for the footprints in the layout excerpt that follows; sources: Cadence DE-HDL packaged netlist, KiCad conversion of 03242023_DA0F0TMBIJ0_F0T_Motherboard_J_brd_V01_OCP.brd

R2406  Q_RES  10K 1% EMPTY  pkg 0402LF  page 281 : A = P3V3_AUX ; B = FM_PVPP_HBM_CPU0_EN
PR108  Q_RES  0 5% CHIP  pkg 0402LF  page 274 : A = P12V_AUX ; B = PVCCINFAON_CPU0_VIN_CSNIN

(kicad_pcb
	(version 20260206)
	(generator "pcbnew")
	(generator_version "10.0")
	(general
		(thickness 1.6)
		(legacy_teardrops no)
	)
	(paper "A4")
	(title_block
		(title "03242023_DA0F0TMBIJ0_F0T_Motherboard_J_brd_V01_OCP.brd")
		(comment 1 "Grand Teton / footprints 5066-5067 of 6105")
	)
	(layers
		(0 "F.Cu" signal "TOP")
		(4 "In1.Cu" signal "GND")
		(6 "In2.Cu" signal "IN1")
		(8 "In3.Cu" signal "GND1")
		(10 "In4.Cu" signal "IN2")
		(12 "In5.Cu" signal "GND2")
		(14 "In6.Cu" signal "IN3")
		(16 "In7.Cu" signal "GND3")
		(18 "In8.Cu" signal "VCC")
		(20 "In9.Cu" signal "VCC1")
		(22 "In10.Cu" signal "GND4")
		(24 "In11.Cu" signal "IN4")
		(26 "In12.Cu" signal "GND5")
		(28 "In13.Cu" signal "IN5")
		(30 "In14.Cu" signal "GND6")
		(32 "In15.Cu" signal "IN6")
		(34 "In16.Cu" signal "GND7")
		(2 "B.Cu" signal "BOTTOM")
		(9 "F.Adhes" user "F.Adhesive")
		(11 "B.Adhes" user "B.Adhesive")
		(13 "F.Paste" user "Package Geometry/Pastemask Top")
		(15 "B.Paste" user "Package Geometry/Pastemask Bottom")
		(5 "F.SilkS" user "Ref Des/Silkscreen Top")
		(7 "B.SilkS" user "Ref Des/Silkscreen Bottom")
		(1 "F.Mask" user "Board Geometry/Soldermask Top")
		(3 "B.Mask" user "Board Geometry/Soldermask Bottom")
		(17 "Dwgs.User" user "User.Drawings")
		(19 "Cmts.User" user "User.Comments")
		(21 "Eco1.User" user "User.Eco1")
		(23 "Eco2.User" user "User.Eco2")
		(25 "Edge.Cuts" user "Board Geometry/Outline")
		(27 "Margin" user)
		(31 "F.CrtYd" user "Package Geometry/Place Bound Top")
		(29 "B.CrtYd" user "Package Geometry/Place Bound Bottom")
		(35 "F.Fab" user "Ref Des/Assembly Top")
		(33 "B.Fab" user "Ref Des/Assembly Bottom")
	)
	(footprint ""
		(layer "B.Cu")
		(at 420.682166 -135.146034 180)
		(property "Reference" "PR108"
			(at 0 0 0)
			(layer "B.SilkS")
			(hide yes)
			(effects
				(font
					(size 1.27 1.27)
				)
				(justify mirror)
			)
		)
		(property "Value" ""
			(at 0 0 0)
			(layer "B.Fab")
			(effects
				(font
					(size 1.27 1.27)
				)
				(justify mirror)
			)
		)
		(duplicate_pad_numbers_are_jumpers no)
		(fp_line
			(start 0.7874 0.4064)
			(end 0.7874 -0.4064)
			(stroke
				(width 0.1524)
				(type default)
			)
			(layer "B.SilkS")
		)
		(fp_line
			(start 0.7874 -0.4064)
			(end -0.7874 -0.4064)
			(stroke
				(width 0.1524)
				(type default)
			)
			(layer "B.SilkS")
		)
		(fp_line
			(start -0.7874 0.4064)
			(end 0.7874 0.4064)
			(stroke
				(width 0.1524)
				(type default)
			)
			(layer "B.SilkS")
		)
		(fp_line
			(start -0.7874 -0.4064)
			(end -0.7874 0.4064)
			(stroke
				(width 0.1524)
				(type default)
			)
			(layer "B.SilkS")
		)
		(fp_line
			(start 0.67945 0.3048)
			(end 0.67945 -0.305054)
			(stroke
				(width 0.1)
				(type default)
			)
			(layer "B.Fab")
		)
		(fp_line
			(start 0.67945 -0.305054)
			(end 0.12065 -0.305054)
			(stroke
				(width 0.1)
				(type default)
			)
			(layer "B.Fab")
		)
		(fp_line
			(start 0.12065 0.3048)
			(end 0.67945 0.3048)
			(stroke
				(width 0.1)
				(type default)
			)
			(layer "B.Fab")
		)
		(fp_line
			(start 0.12065 0.2794)
			(end 0.12065 0.3048)
			(stroke
				(width 0.1)
				(type default)
			)
			(layer "B.Fab")
		)
		(fp_line
			(start 0.12065 -0.2794)
			(end -0.12065 -0.2794)
			(stroke
				(width 0.1)
				(type default)
			)
			(layer "B.Fab")
		)
		(fp_line
			(start 0.12065 -0.305054)
			(end 0.12065 -0.2794)
			(stroke
				(width 0.1)
				(type default)
			)
			(layer "B.Fab")
		)
		(fp_line
			(start -0.120396 0.3048)
			(end -0.120396 0.2794)
			(stroke
				(width 0.1)
				(type default)
			)
			(layer "B.Fab")
		)
		(fp_line
			(start -0.120396 0.2794)
			(end 0.12065 0.2794)
			(stroke
				(width 0.1)
				(type default)
			)
			(layer "B.Fab")
		)
		(fp_line
			(start -0.12065 -0.2794)
			(end -0.12065 -0.3048)
			(stroke
				(width 0.1)
				(type default)
			)
			(layer "B.Fab")
		)
		(fp_line
			(start -0.12065 -0.3048)
			(end -0.67945 -0.3048)
			(stroke
				(width 0.1)
				(type default)
			)
			(layer "B.Fab")
		)
		(fp_line
			(start -0.67945 0.3048)
			(end -0.120396 0.3048)
			(stroke
				(width 0.1)
				(type default)
			)
			(layer "B.Fab")
		)
		(fp_line
			(start -0.67945 -0.3048)
			(end -0.67945 0.3048)
			(stroke
				(width 0.1)
				(type default)
			)
			(layer "B.Fab")
		)
		(pad "1" smd circle
			(at 0.40005 0)
			(size 0 0)
			(layers "B.Cu" "B.Mask" "B.Paste")
			(net "P12V_AUX")
		)
		(pad "2" smd circle
			(at -0.40005 0)
			(size 0 0)
			(layers "B.Cu" "B.Mask" "B.Paste")
			(net "PVCCINFAON_CPU0_VIN_CSNIN")
		)
	)
	(footprint ""
		(layer "B.Cu")
		(at 369.756436 -354.93833 -90)
		(property "Reference" "R2406"
			(at 0 0 90)
			(layer "B.SilkS")
			(hide yes)
			(effects
				(font
					(size 1.27 1.27)
				)
				(justify mirror)
			)
		)
		(property "Value" ""
			(at 0 0 90)
			(layer "B.Fab")
			(effects
				(font
					(size 1.27 1.27)
				)
				(justify mirror)
			)
		)
		(duplicate_pad_numbers_are_jumpers no)
		(fp_line
			(start -0.7874 0.4064)
			(end 0.7874 0.4064)
			(stroke
				(width 0.1524)
				(type default)
			)
			(layer "B.SilkS")
		)
		(fp_line
			(start 0.7874 0.4064)
			(end 0.7874 -0.4064)
			(stroke
				(width 0.1524)
				(type default)
			)
			(layer "B.SilkS")
		)
		(fp_line
			(start -0.7874 -0.4064)
			(end -0.7874 0.4064)
			(stroke
				(width 0.1524)
				(type default)
			)
			(layer "B.SilkS")
		)
		(fp_line
			(start 0.7874 -0.4064)
			(end -0.7874 -0.4064)
			(stroke
				(width 0.1524)
				(type default)
			)
			(layer "B.SilkS")
		)
		(fp_line
			(start -0.67945 0.3048)
			(end -0.120396 0.3048)
			(stroke
				(width 0.1)
				(type default)
			)
			(layer "B.Fab")
		)
		(fp_line
			(start -0.120396 0.3048)
			(end -0.120396 0.2794)
			(stroke
				(width 0.1)
				(type default)
			)
			(layer "B.Fab")
		)
		(fp_line
			(start 0.12065 0.3048)
			(end 0.67945 0.3048)
			(stroke
				(width 0.1)
				(type default)
			)
			(layer "B.Fab")
		)
		(fp_line
			(start 0.67945 0.3048)
			(end 0.67945 -0.305054)
			(stroke
				(width 0.1)
				(type default)
			)
			(layer "B.Fab")
		)
		(fp_line
			(start -0.120396 0.2794)
			(end 0.12065 0.2794)
			(stroke
				(width 0.1)
				(type default)
			)
			(layer "B.Fab")
		)
		(fp_line
			(start 0.12065 0.2794)
			(end 0.12065 0.3048)
			(stroke
				(width 0.1)
				(type default)
			)
			(layer "B.Fab")
		)
		(fp_line
			(start -0.12065 -0.2794)
			(end -0.12065 -0.3048)
			(stroke
				(width 0.1)
				(type default)
			)
			(layer "B.Fab")
		)
		(fp_line
			(start 0.12065 -0.2794)
			(end -0.12065 -0.2794)
			(stroke
				(width 0.1)
				(type default)
			)
			(layer "B.Fab")
		)
		(fp_line
			(start -0.67945 -0.3048)
			(end -0.67945 0.3048)
			(stroke
				(width 0.1)
				(type default)
			)
			(layer "B.Fab")
		)
		(fp_line
			(start -0.12065 -0.3048)
			(end -0.67945 -0.3048)
			(stroke
				(width 0.1)
				(type default)
			)
			(layer "B.Fab")
		)
		(fp_line
			(start 0.12065 -0.305054)
			(end 0.12065 -0.2794)
			(stroke
				(width 0.1)
				(type default)
			)
			(layer "B.Fab")
		)
		(fp_line
			(start 0.67945 -0.305054)
			(end 0.12065 -0.305054)
			(stroke
				(width 0.1)
				(type default)
			)
			(layer "B.Fab")
		)
		(pad "1" smd circle
			(at 0.40005 0 90)
			(size 0 0)
			(layers "B.Cu" "B.Mask" "B.Paste")
			(net "P3V3_AUX")
		)
		(pad "2" smd circle
			(at -0.40005 0 90)
			(size 0 0)
			(layers "B.Cu" "B.Mask" "B.Paste")
			(net "FM_PVPP_HBM_CPU0_EN")
		)
	)
)
